(kicad_pcb
	(version 20260206)
	(generator "pcbnew")
	(generator_version "10.0")
	(general
		(thickness 1.6)
		(legacy_teardrops no)
	)
	(paper "A4")
	(title_block
		(title "Bryce Canyon_IOM_IOC_16318-2_OCP.brd")
		(comment 1 "Bryce Canyon / footprints 60-67 of 1605")
	)
	(layers
		(0 "F.Cu" signal "TOP")
		(4 "In1.Cu" signal "L2GND")
		(6 "In2.Cu" signal "L3")
		(8 "In3.Cu" signal "L4VCC")
		(10 "In4.Cu" signal "L5VCC")
		(12 "In5.Cu" signal "L6")
		(14 "In6.Cu" signal "L7GND")
		(2 "B.Cu" signal "BOTTOM")
		(9 "F.Adhes" user "F.Adhesive")
		(11 "B.Adhes" user "B.Adhesive")
		(13 "F.Paste" user "Package Geometry/Pastemask Top")
		(15 "B.Paste" user "Package Geometry/Pastemask Bottom")
		(5 "F.SilkS" user "Ref Des/Silkscreen Top")
		(7 "B.SilkS" user "Ref Des/Silkscreen Bottom")
		(1 "F.Mask" user "Board Geometry/Soldermask Top")
		(3 "B.Mask" user "Board Geometry/Soldermask Bottom")
		(17 "Dwgs.User" user "User.Drawings")
		(19 "Cmts.User" user "User.Comments")
		(21 "Eco1.User" user "User.Eco1")
		(23 "Eco2.User" user "User.Eco2")
		(25 "Edge.Cuts" user "Board Geometry/Outline")
		(27 "Margin" user)
		(31 "F.CrtYd" user "Package Geometry/Place Bound Top")
		(29 "B.CrtYd" user "Package Geometry/Place Bound Bottom")
		(35 "F.Fab" user "Ref Des/Assembly Top")
		(33 "B.Fab" user "Ref Des/Assembly Bottom")
	)
	(footprint ""
		(layer "F.Cu")
		(at 74.4728 -140.0302 -90)
		(property "Reference" "R58"
			(at 0 0 270)
			(layer "F.SilkS")
			(hide yes)
			(effects
				(font
					(size 1.27 1.27)
				)
			)
		)
		(property "Value" "33R2F-3-GP"
			(at 0.064008 -3.993896 270)
			(unlocked yes)
			(layer "F.Fab")
			(hide yes)
			(effects
				(font
					(size 1.016 1.016)
					(thickness 0.1524)
				)
			)
		)
		(property "Device Type" "R402H16"
			(at 0.064008 -5.517896 270)
			(unlocked yes)
			(layer "F.Fab")
			(hide yes)
			(effects
				(font
					(size 1.016 1.016)
					(thickness 0.1524)
				)
			)
		)
		(duplicate_pad_numbers_are_jumpers no)
		(fp_line
			(start -0.508 -0.9398)
			(end -0.508 0.9398)
			(stroke
				(width 0.1524)
				(type default)
			)
			(layer "F.SilkS")
		)
		(fp_line
			(start 0.508 -0.9398)
			(end -0.508 -0.9398)
			(stroke
				(width 0.1524)
				(type default)
			)
			(layer "F.SilkS")
		)
		(fp_rect
			(start -0.508 0.9398)
			(end 0.508 -0.9398)
			(stroke
				(width 0)
				(type default)
			)
			(fill no)
			(layer "F.CrtYd")
		)
		(fp_rect
			(start -0.508 0.9398)
			(end 0.508 -0.9398)
			(stroke
				(width 0)
				(type default)
			)
			(fill no)
			(layer "F.Fab")
		)
		(pad "1" smd custom
			(at 0 -0.4445 270)
			(size 0.1397 0.1397)
			(layers "F.Cu" "F.Mask" "F.Paste")
			(net "SYS_RST_BTN_IN_N")
			(options
				(clearance outline)
				(anchor circle)
			)
			(primitives
				(gr_poly
					(pts
						(arc
							(start -0.1778 -0.2794)
							(mid -0.249642 -0.249642)
							(end -0.2794 -0.1778)
						)
						(arc
							(start -0.2794 0.1778)
							(mid -0.249642 0.249642)
							(end -0.1778 0.2794)
						)
						(arc
							(start 0.1778 0.2794)
							(mid 0.249642 0.249642)
							(end 0.2794 0.1778)
						)
						(arc
							(start 0.2794 -0.1778)
							(mid 0.249642 -0.249642)
							(end 0.1778 -0.2794)
						)
					)
					(width 0)
					(fill yes)
				)
			)
		)
		(pad "2" smd custom
			(at 0 0.4445 270)
			(size 0.1397 0.1397)
			(layers "F.Cu" "F.Mask" "F.Paste")
			(net "FP_RESET_RC_N")
			(options
				(clearance outline)
				(anchor circle)
			)
			(primitives
				(gr_poly
					(pts
						(arc
							(start -0.1778 -0.2794)
							(mid -0.249642 -0.249642)
							(end -0.2794 -0.1778)
						)
						(arc
							(start -0.2794 0.1778)
							(mid -0.249642 0.249642)
							(end -0.1778 0.2794)
						)
						(arc
							(start 0.1778 0.2794)
							(mid 0.249642 0.249642)
							(end 0.2794 0.1778)
						)
						(arc
							(start 0.2794 -0.1778)
							(mid 0.249642 -0.249642)
							(end 0.1778 -0.2794)
						)
					)
					(width 0)
					(fill yes)
				)
			)
		)
	)
	(footprint ""
		(layer "F.Cu")
		(at 83.358228 -88.549734 90)
		(property "Reference" "VIA13"
			(at 0 0 90)
			(layer "F.SilkS")
			(hide yes)
			(effects
				(font
					(size 1.27 1.27)
				)
			)
		)
		(property "Value" "85OHM-8L-1D6MM-L16L18-GP"
			(at 4.064 0.6096 90)
			(unlocked yes)
			(layer "F.Fab")
			(hide yes)
			(effects
				(font
					(size 1.016 1.016)
					(thickness 0.1524)
				)
			)
		)
		(property "Device Type" "VIA-PCIE-4P-368076"
			(at 4.064 -0.9144 90)
			(unlocked yes)
			(layer "F.Fab")
			(hide yes)
			(effects
				(font
					(size 1.016 1.016)
					(thickness 0.1524)
				)
			)
		)
		(duplicate_pad_numbers_are_jumpers no)
		(fp_rect
			(start -1.8415 0.381)
			(end 1.8415 -0.381)
			(stroke
				(width 0)
				(type default)
			)
			(fill no)
			(layer "F.CrtYd")
		)
		(fp_rect
			(start -1.8415 0.381)
			(end 1.8415 -0.381)
			(stroke
				(width 0)
				(type default)
			)
			(fill no)
			(layer "F.Fab")
		)
		(pad "1" thru_hole circle
			(at -1.4605 0 90)
			(size 0.508 0.508)
			(drill 0.254)
			(layers "*.Cu" "*.Mask")
			(remove_unused_layers no)
			(net "GND")
			(clearance 0.127)
			(thermal_gap 0.127)
		)
		(pad "2" thru_hole circle
			(at -0.4445 0 90)
			(size 0.508 0.508)
			(drill 0.254)
			(layers "*.Cu" "*.Mask")
			(remove_unused_layers no)
			(net "PCIE_IOM_TO_COMP_21_DP")
			(clearance 0.127)
			(thermal_gap 0.127)
		)
		(pad "3" thru_hole circle
			(at 0.4445 0 90)
			(size 0.508 0.508)
			(drill 0.254)
			(layers "*.Cu" "*.Mask")
			(remove_unused_layers no)
			(net "PCIE_IOM_TO_COMP_21_DN")
			(clearance 0.127)
			(thermal_gap 0.127)
		)
		(pad "4" thru_hole circle
			(at 1.4605 0 90)
			(size 0.508 0.508)
			(drill 0.254)
			(layers "*.Cu" "*.Mask")
			(remove_unused_layers no)
			(net "GND")
			(clearance 0.127)
			(thermal_gap 0.127)
		)
	)
	(footprint ""
		(layer "F.Cu")
		(at 10.796524 -136.715246 90)
		(property "Reference" "R208"
			(at 0 0 90)
			(layer "F.SilkS")
			(hide yes)
			(effects
				(font
					(size 1.27 1.27)
				)
			)
		)
		(property "Value" "120R2F-GP"
			(at 0.064008 -3.993896 90)
			(unlocked yes)
			(layer "F.Fab")
			(hide yes)
			(effects
				(font
					(size 1.016 1.016)
					(thickness 0.1524)
				)
			)
		)
		(property "Device Type" "R402H16"
			(at 0.064008 -5.517896 90)
			(unlocked yes)
			(layer "F.Fab")
			(hide yes)
			(effects
				(font
					(size 1.016 1.016)
					(thickness 0.1524)
				)
			)
		)
		(duplicate_pad_numbers_are_jumpers no)
		(fp_line
			(start 0.508 -0.9398)
			(end -0.508 -0.9398)
			(stroke
				(width 0.1524)
				(type default)
			)
			(layer "F.SilkS")
		)
		(fp_line
			(start -0.508 -0.9398)
			(end -0.508 0.9398)
			(stroke
				(width 0.1524)
				(type default)
			)
			(layer "F.SilkS")
		)
		(fp_rect
			(start -0.508 0.9398)
			(end 0.508 -0.9398)
			(stroke
				(width 0)
				(type default)
			)
			(fill no)
			(layer "F.CrtYd")
		)
		(fp_rect
			(start -0.508 0.9398)
			(end 0.508 -0.9398)
			(stroke
				(width 0)
				(type default)
			)
			(fill no)
			(layer "F.Fab")
		)
		(pad "1" smd custom
			(at 0 -0.4445 90)
			(size 0.1397 0.1397)
			(layers "F.Cu" "F.Mask" "F.Paste")
			(net "DDR4_RST_N")
			(options
				(clearance outline)
				(anchor circle)
			)
			(primitives
				(gr_poly
					(pts
						(arc
							(start -0.1778 -0.2794)
							(mid -0.249642 -0.249642)
							(end -0.2794 -0.1778)
						)
						(arc
							(start -0.2794 0.1778)
							(mid -0.249642 0.249642)
							(end -0.1778 0.2794)
						)
						(arc
							(start 0.1778 0.2794)
							(mid 0.249642 0.249642)
							(end 0.2794 0.1778)
						)
						(arc
							(start 0.2794 -0.1778)
							(mid 0.249642 -0.249642)
							(end 0.1778 -0.2794)
						)
					)
					(width 0)
					(fill yes)
				)
			)
		)
		(pad "2" smd custom
			(at 0 0.4445 90)
			(size 0.1397 0.1397)
			(layers "F.Cu" "F.Mask" "F.Paste")
			(net "P1V2_STBY")
			(options
				(clearance outline)
				(anchor circle)
			)
			(primitives
				(gr_poly
					(pts
						(arc
							(start -0.1778 -0.2794)
							(mid -0.249642 -0.249642)
							(end -0.2794 -0.1778)
						)
						(arc
							(start -0.2794 0.1778)
							(mid -0.249642 0.249642)
							(end -0.1778 0.2794)
						)
						(arc
							(start 0.1778 0.2794)
							(mid 0.249642 0.249642)
							(end 0.2794 0.1778)
						)
						(arc
							(start 0.2794 -0.1778)
							(mid 0.249642 -0.249642)
							(end 0.1778 -0.2794)
						)
					)
					(width 0)
					(fill yes)
				)
			)
		)
	)
	(footprint ""
		(layer "F.Cu")
		(at 120.015 -16.3068)
		(property "Reference" "R441"
			(at 0 0 0)
			(layer "F.SilkS")
			(hide yes)
			(effects
				(font
					(size 1.27 1.27)
				)
			)
		)
		(property "Value" "10R2F-L-GP"
			(at 0.064008 -3.993896 0)
			(unlocked yes)
			(layer "F.Fab")
			(hide yes)
			(effects
				(font
					(size 1.016 1.016)
					(thickness 0.1524)
				)
			)
		)
		(property "Device Type" "R402H14"
			(at 0.064008 -5.517896 0)
			(unlocked yes)
			(layer "F.Fab")
			(hide yes)
			(effects
				(font
					(size 1.016 1.016)
					(thickness 0.1524)
				)
			)
		)
		(duplicate_pad_numbers_are_jumpers no)
		(fp_line
			(start -0.508 -0.9398)
			(end -0.508 0.9398)
			(stroke
				(width 0.1524)
				(type default)
			)
			(layer "F.SilkS")
		)
		(fp_line
			(start 0.508 -0.9398)
			(end -0.508 -0.9398)
			(stroke
				(width 0.1524)
				(type default)
			)
			(layer "F.SilkS")
		)
		(fp_rect
			(start -0.508 0.9398)
			(end 0.508 -0.9398)
			(stroke
				(width 0)
				(type default)
			)
			(fill no)
			(layer "F.CrtYd")
		)
		(fp_rect
			(start -0.508 0.9398)
			(end 0.508 -0.9398)
			(stroke
				(width 0)
				(type default)
			)
			(fill no)
			(layer "F.Fab")
		)
		(pad "1" smd custom
			(at 0 -0.4445)
			(size 0.1397 0.1397)
			(layers "F.Cu" "F.Mask" "F.Paste")
			(net "MB0_CM_SENSE_R1_N")
			(options
				(clearance outline)
				(anchor circle)
			)
			(primitives
				(gr_poly
					(pts
						(arc
							(start -0.1778 -0.2794)
							(mid -0.249642 -0.249642)
							(end -0.2794 -0.1778)
						)
						(arc
							(start -0.2794 0.1778)
							(mid -0.249642 0.249642)
							(end -0.1778 0.2794)
						)
						(arc
							(start 0.1778 0.2794)
							(mid 0.249642 0.249642)
							(end 0.2794 0.1778)
						)
						(arc
							(start 0.2794 -0.1778)
							(mid 0.249642 -0.249642)
							(end 0.1778 -0.2794)
						)
					)
					(width 0)
					(fill yes)
				)
			)
		)
		(pad "2" smd custom
			(at 0 0.4445)
			(size 0.1397 0.1397)
			(layers "F.Cu" "F.Mask" "F.Paste")
			(net "MB0_CM_SENSE_N")
			(options
				(clearance outline)
				(anchor circle)
			)
			(primitives
				(gr_poly
					(pts
						(arc
							(start -0.1778 -0.2794)
							(mid -0.249642 -0.249642)
							(end -0.2794 -0.1778)
						)
						(arc
							(start -0.2794 0.1778)
							(mid -0.249642 0.249642)
							(end -0.1778 0.2794)
						)
						(arc
							(start 0.1778 0.2794)
							(mid 0.249642 0.249642)
							(end 0.2794 0.1778)
						)
						(arc
							(start 0.2794 -0.1778)
							(mid 0.249642 -0.249642)
							(end 0.1778 -0.2794)
						)
					)
					(width 0)
					(fill yes)
				)
			)
		)
	)
	(footprint ""
		(layer "F.Cu")
		(at 32.4866 -165.0238)
		(property "Reference" "R698"
			(at 0 0 0)
			(layer "F.SilkS")
			(hide yes)
			(effects
				(font
					(size 1.27 1.27)
				)
			)
		)
		(property "Value" "4K7R2F-GP"
			(at 0.064008 -3.993896 0)
			(unlocked yes)
			(layer "F.Fab")
			(hide yes)
			(effects
				(font
					(size 1.016 1.016)
					(thickness 0.1524)
				)
			)
		)
		(property "Device Type" "R402H16"
			(at 0.064008 -5.517896 0)
			(unlocked yes)
			(layer "F.Fab")
			(hide yes)
			(effects
				(font
					(size 1.016 1.016)
					(thickness 0.1524)
				)
			)
		)
		(duplicate_pad_numbers_are_jumpers no)
		(fp_line
			(start -0.508 -0.9398)
			(end -0.508 0.9398)
			(stroke
				(width 0.1524)
				(type default)
			)
			(layer "F.SilkS")
		)
		(fp_line
			(start 0.508 -0.9398)
			(end -0.508 -0.9398)
			(stroke
				(width 0.1524)
				(type default)
			)
			(layer "F.SilkS")
		)
		(fp_rect
			(start -0.508 0.9398)
			(end 0.508 -0.9398)
			(stroke
				(width 0)
				(type default)
			)
			(fill no)
			(layer "F.CrtYd")
		)
		(fp_rect
			(start -0.508 0.9398)
			(end 0.508 -0.9398)
			(stroke
				(width 0)
				(type default)
			)
			(fill no)
			(layer "F.Fab")
		)
		(pad "1" smd custom
			(at 0 -0.4445)
			(size 0.1397 0.1397)
			(layers "F.Cu" "F.Mask" "F.Paste")
			(net "P3V3_STBY")
			(options
				(clearance outline)
				(anchor circle)
			)
			(primitives
				(gr_poly
					(pts
						(arc
							(start -0.1778 -0.2794)
							(mid -0.249642 -0.249642)
							(end -0.2794 -0.1778)
						)
						(arc
							(start -0.2794 0.1778)
							(mid -0.249642 0.249642)
							(end -0.1778 0.2794)
						)
						(arc
							(start 0.1778 0.2794)
							(mid 0.249642 0.249642)
							(end 0.2794 0.1778)
						)
						(arc
							(start 0.2794 -0.1778)
							(mid 0.249642 -0.249642)
							(end 0.1778 -0.2794)
						)
					)
					(width 0)
					(fill yes)
				)
			)
		)
		(pad "2" smd custom
			(at 0 0.4445)
			(size 0.1397 0.1397)
			(layers "F.Cu" "F.Mask" "F.Paste")
			(net "IOM_TYPE1")
			(options
				(clearance outline)
				(anchor circle)
			)
			(primitives
				(gr_poly
					(pts
						(arc
							(start -0.1778 -0.2794)
							(mid -0.249642 -0.249642)
							(end -0.2794 -0.1778)
						)
						(arc
							(start -0.2794 0.1778)
							(mid -0.249642 0.249642)
							(end -0.1778 0.2794)
						)
						(arc
							(start 0.1778 0.2794)
							(mid 0.249642 0.249642)
							(end 0.2794 0.1778)
						)
						(arc
							(start 0.2794 -0.1778)
							(mid 0.249642 -0.249642)
							(end 0.1778 -0.2794)
						)
					)
					(width 0)
					(fill yes)
				)
			)
		)
	)
	(footprint ""
		(layer "F.Cu")
		(at 176.9618 -119.7864 180)
		(property "Reference" "R523"
			(at 0 0 180)
			(layer "F.SilkS")
			(hide yes)
			(effects
				(font
					(size 1.27 1.27)
				)
			)
		)
		(property "Value" "4K53R2F-1-GP"
			(at 0.064008 -3.993896 180)
			(unlocked yes)
			(layer "F.Fab")
			(hide yes)
			(effects
				(font
					(size 1.016 1.016)
					(thickness 0.1524)
				)
			)
		)
		(property "Device Type" "R402H16"
			(at 0.064008 -5.517896 180)
			(unlocked yes)
			(layer "F.Fab")
			(hide yes)
			(effects
				(font
					(size 1.016 1.016)
					(thickness 0.1524)
				)
			)
		)
		(duplicate_pad_numbers_are_jumpers no)
		(fp_line
			(start 0.508 -0.9398)
			(end -0.508 -0.9398)
			(stroke
				(width 0.1524)
				(type default)
			)
			(layer "F.SilkS")
		)
		(fp_line
			(start -0.508 -0.9398)
			(end -0.508 0.9398)
			(stroke
				(width 0.1524)
				(type default)
			)
			(layer "F.SilkS")
		)
		(fp_rect
			(start -0.508 0.9398)
			(end 0.508 -0.9398)
			(stroke
				(width 0)
				(type default)
			)
			(fill no)
			(layer "F.CrtYd")
		)
		(fp_rect
			(start -0.508 0.9398)
			(end 0.508 -0.9398)
			(stroke
				(width 0)
				(type default)
			)
			(fill no)
			(layer "F.Fab")
		)
		(pad "1" smd custom
			(at 0 -0.4445 180)
			(size 0.1397 0.1397)
			(layers "F.Cu" "F.Mask" "F.Paste")
			(net "PQ4_G")
			(options
				(clearance outline)
				(anchor circle)
			)
			(primitives
				(gr_poly
					(pts
						(arc
							(start -0.1778 -0.2794)
							(mid -0.249642 -0.249642)
							(end -0.2794 -0.1778)
						)
						(arc
							(start -0.2794 0.1778)
							(mid -0.249642 0.249642)
							(end -0.1778 0.2794)
						)
						(arc
							(start 0.1778 0.2794)
							(mid 0.249642 0.249642)
							(end 0.2794 0.1778)
						)
						(arc
							(start 0.2794 -0.1778)
							(mid 0.249642 -0.249642)
							(end 0.1778 -0.2794)
						)
					)
					(width 0)
					(fill yes)
				)
			)
		)
		(pad "2" smd custom
			(at 0 0.4445 180)
			(size 0.1397 0.1397)
			(layers "F.Cu" "F.Mask" "F.Paste")
			(net "P3V3_STBY")
			(options
				(clearance outline)
				(anchor circle)
			)
			(primitives
				(gr_poly
					(pts
						(arc
							(start -0.1778 -0.2794)
							(mid -0.249642 -0.249642)
							(end -0.2794 -0.1778)
						)
						(arc
							(start -0.2794 0.1778)
							(mid -0.249642 0.249642)
							(end -0.1778 0.2794)
						)
						(arc
							(start 0.1778 0.2794)
							(mid 0.249642 0.249642)
							(end 0.2794 0.1778)
						)
						(arc
							(start 0.2794 -0.1778)
							(mid 0.249642 -0.249642)
							(end 0.1778 -0.2794)
						)
					)
					(width 0)
					(fill yes)
				)
			)
		)
	)
	(footprint ""
		(layer "F.Cu")
		(at 205.574646 -17.357344 180)
		(property "Reference" "R609"
			(at 0 0 180)
			(layer "F.SilkS")
			(hide yes)
			(effects
				(font
					(size 1.27 1.27)
				)
			)
		)
		(property "Value" "0R2J-2-GP"
			(at 0.064008 -3.993896 180)
			(unlocked yes)
			(layer "F.Fab")
			(hide yes)
			(effects
				(font
					(size 1.016 1.016)
					(thickness 0.1524)
				)
			)
		)
		(property "Device Type" "R402H16"
			(at 0.064008 -5.517896 180)
			(unlocked yes)
			(layer "F.Fab")
			(hide yes)
			(effects
				(font
					(size 1.016 1.016)
					(thickness 0.1524)
				)
			)
		)
		(duplicate_pad_numbers_are_jumpers no)
		(fp_line
			(start 0.508 -0.9398)
			(end -0.508 -0.9398)
			(stroke
				(width 0.1524)
				(type default)
			)
			(layer "F.SilkS")
		)
		(fp_line
			(start -0.508 -0.9398)
			(end -0.508 0.9398)
			(stroke
				(width 0.1524)
				(type default)
			)
			(layer "F.SilkS")
		)
		(fp_rect
			(start -0.508 0.9398)
			(end 0.508 -0.9398)
			(stroke
				(width 0)
				(type default)
			)
			(fill no)
			(layer "F.CrtYd")
		)
		(fp_rect
			(start -0.508 0.9398)
			(end 0.508 -0.9398)
			(stroke
				(width 0)
				(type default)
			)
			(fill no)
			(layer "F.Fab")
		)
		(pad "1" smd custom
			(at 0 -0.4445 180)
			(size 0.1397 0.1397)
			(layers "F.Cu" "F.Mask" "F.Paste")
			(net "BMC_ML_PWR_YELLOW_LED_R")
			(options
				(clearance outline)
				(anchor circle)
			)
			(primitives
				(gr_poly
					(pts
						(arc
							(start -0.1778 -0.2794)
							(mid -0.249642 -0.249642)
							(end -0.2794 -0.1778)
						)
						(arc
							(start -0.2794 0.1778)
							(mid -0.249642 0.249642)
							(end -0.1778 0.2794)
						)
						(arc
							(start 0.1778 0.2794)
							(mid 0.249642 0.249642)
							(end 0.2794 0.1778)
						)
						(arc
							(start 0.2794 -0.1778)
							(mid 0.249642 -0.249642)
							(end 0.1778 -0.2794)
						)
					)
					(width 0)
					(fill yes)
				)
			)
		)
		(pad "2" smd custom
			(at 0 0.4445 180)
			(size 0.1397 0.1397)
			(layers "F.Cu" "F.Mask" "F.Paste")
			(net "BMC_ML_PWR_YELLOW_LED")
			(options
				(clearance outline)
				(anchor circle)
			)
			(primitives
				(gr_poly
					(pts
						(arc
							(start -0.1778 -0.2794)
							(mid -0.249642 -0.249642)
							(end -0.2794 -0.1778)
						)
						(arc
							(start -0.2794 0.1778)
							(mid -0.249642 0.249642)
							(end -0.1778 0.2794)
						)
						(arc
							(start 0.1778 0.2794)
							(mid 0.249642 0.249642)
							(end 0.2794 0.1778)
						)
						(arc
							(start 0.2794 -0.1778)
							(mid 0.249642 -0.249642)
							(end 0.1778 -0.2794)
						)
					)
					(width 0)
					(fill yes)
				)
			)
		)
	)
	(footprint ""
		(layer "F.Cu")
		(at 169.037 -176.911 -90)
		(property "Reference" "C165"
			(at 0 0 270)
			(layer "F.SilkS")
			(hide yes)
			(effects
				(font
					(size 1.27 1.27)
				)
			)
		)
		(property "Value" "SC10U16V5KX-7-GP-U"
			(at -0.0762 -6.1214 270)
			(unlocked yes)
			(layer "F.Fab")
			(hide yes)
			(effects
				(font
					(size 1.016 1.016)
					(thickness 0.1524)
				)
			)
		)
		(property "Device Type" "C805H58"
			(at -0.0762 -8.1534 270)
			(unlocked yes)
			(layer "F.Fab")
			(hide yes)
			(effects
				(font
					(size 1.016 1.016)
					(thickness 0.1524)
				)
			)
		)
		(duplicate_pad_numbers_are_jumpers no)
		(fp_line
			(start 0.635 0)
			(end -0.635 0)
			(stroke
				(width 0.508)
				(type default)
			)
			(layer "F.SilkS")
		)
		(fp_rect
			(start -0.9652 1.778)
			(end 0.9652 -1.778)
			(stroke
				(width 0)
				(type default)
			)
			(fill no)
			(layer "F.CrtYd")
		)
		(fp_poly
			(pts
				(xy -0.9652 -1.778) (xy 0.9652 -1.778) (xy 0.9652 1.778) (xy -0.9652 1.778)
			)
			(stroke
				(width 0)
				(type default)
			)
			(fill no)
			(layer "F.Fab")
		)
		(pad "1" smd rect
			(at 0 -0.9652 270)
			(size 1.397 1.143)
			(layers "F.Cu" "F.Mask" "F.Paste")
			(net "P5V_STBY")
		)
		(pad "2" smd rect
			(at 0 0.9652 270)
			(size 1.397 1.143)
			(layers "F.Cu" "F.Mask" "F.Paste")
			(net "GND")
		)
	)
)
